(kicad_pcb
	(version 20260206)
	(generator "pcbnew")
	(generator_version "10.0")
	(general
		(thickness 1.6)
		(legacy_teardrops no)
	)
	(paper "A4")
	(title_block
		(title "04192023_DAF0TMB3IC0_F0TG_MB_C_brd_V02_OCP.brd")
		(comment 1 "Grand Teton / footprints 2928-2928 of 8354")
	)
	(layers
		(0 "F.Cu" signal "TOP")
		(4 "In1.Cu" signal "GND")
		(6 "In2.Cu" signal "IN1")
		(8 "In3.Cu" signal "GND1")
		(10 "In4.Cu" signal "IN2")
		(12 "In5.Cu" signal "GND2")
		(14 "In6.Cu" signal "IN3")
		(16 "In7.Cu" signal "GND3")
		(18 "In8.Cu" signal "VCC")
		(20 "In9.Cu" signal "VCC1")
		(22 "In10.Cu" signal "GND4")
		(24 "In11.Cu" signal "IN4")
		(26 "In12.Cu" signal "GND5")
		(28 "In13.Cu" signal "IN5")
		(30 "In14.Cu" signal "GND6")
		(32 "In15.Cu" signal "IN6")
		(34 "In16.Cu" signal "GND7")
		(2 "B.Cu" signal "BOTTOM")
		(9 "F.Adhes" user "F.Adhesive")
		(11 "B.Adhes" user "B.Adhesive")
		(13 "F.Paste" user "Package Geometry/Pastemask Top")
		(15 "B.Paste" user "Package Geometry/Pastemask Bottom")
		(5 "F.SilkS" user "Ref Des/Silkscreen Top")
		(7 "B.SilkS" user "Ref Des/Silkscreen Bottom")
		(1 "F.Mask" user "Board Geometry/Soldermask Top")
		(3 "B.Mask" user "Board Geometry/Soldermask Bottom")
		(17 "Dwgs.User" user "User.Drawings")
		(19 "Cmts.User" user "User.Comments")
		(21 "Eco1.User" user "User.Eco1")
		(23 "Eco2.User" user "User.Eco2")
		(25 "Edge.Cuts" user "Board Geometry/Outline")
		(27 "Margin" user)
		(31 "F.CrtYd" user "Package Geometry/Place Bound Top")
		(29 "B.CrtYd" user "Package Geometry/Place Bound Bottom")
		(35 "F.Fab" user "Ref Des/Assembly Top")
		(33 "B.Fab" user "Ref Des/Assembly Bottom")
	)
	(footprint ""
		(layer "F.Cu")
		(at 198.247 -93.345 180)
		(property "Reference" "R8090"
			(at 0 0 180)
			(layer "F.SilkS")
			(hide yes)
			(effects
				(font
					(size 1.27 1.27)
				)
			)
		)
		(property "Value" ""
			(at 0 0 180)
			(layer "F.Fab")
			(effects
				(font
					(size 1.27 1.27)
				)
			)
		)
		(duplicate_pad_numbers_are_jumpers no)
		(fp_line
			(start 0.7874 0.4064)
			(end -0.7874 0.4064)
			(stroke
				(width 0.1524)
				(type default)
			)
			(layer "F.SilkS")
		)
		(fp_line
			(start 0.7874 -0.4064)
			(end 0.7874 0.4064)
			(stroke
				(width 0.1524)
				(type default)
			)
			(layer "F.SilkS")
		)
		(fp_line
			(start -0.7874 0.4064)
			(end -0.7874 -0.4064)
			(stroke
				(width 0.1524)
				(type default)
			)
			(layer "F.SilkS")
		)
		(fp_line
			(start -0.7874 -0.4064)
			(end 0.7874 -0.4064)
			(stroke
				(width 0.1524)
				(type default)
			)
			(layer "F.SilkS")
		)
		(fp_line
			(start 0.67945 0.3048)
			(end 0.120396 0.3048)
			(stroke
				(width 0.1)
				(type default)
			)
			(layer "F.Fab")
		)
		(fp_line
			(start 0.67945 -0.3048)
			(end 0.67945 0.3048)
			(stroke
				(width 0.1)
				(type default)
			)
			(layer "F.Fab")
		)
		(fp_line
			(start 0.12065 -0.2794)
			(end 0.12065 -0.3048)
			(stroke
				(width 0.1)
				(type default)
			)
			(layer "F.Fab")
		)
		(fp_line
			(start 0.12065 -0.3048)
			(end 0.67945 -0.3048)
			(stroke
				(width 0.1)
				(type default)
			)
			(layer "F.Fab")
		)
		(fp_line
			(start 0.120396 0.3048)
			(end 0.120396 0.2794)
			(stroke
				(width 0.1)
				(type default)
			)
			(layer "F.Fab")
		)
		(fp_line
			(start 0.120396 0.2794)
			(end -0.12065 0.2794)
			(stroke
				(width 0.1)
				(type default)
			)
			(layer "F.Fab")
		)
		(fp_line
			(start -0.12065 0.3048)
			(end -0.67945 0.3048)
			(stroke
				(width 0.1)
				(type default)
			)
			(layer "F.Fab")
		)
		(fp_line
			(start -0.12065 0.2794)
			(end -0.12065 0.3048)
			(stroke
				(width 0.1)
				(type default)
			)
			(layer "F.Fab")
		)
		(fp_line
			(start -0.12065 -0.2794)
			(end 0.12065 -0.2794)
			(stroke
				(width 0.1)
				(type default)
			)
			(layer "F.Fab")
		)
		(fp_line
			(start -0.12065 -0.305054)
			(end -0.12065 -0.2794)
			(stroke
				(width 0.1)
				(type default)
			)
			(layer "F.Fab")
		)
		(fp_line
			(start -0.67945 0.3048)
			(end -0.67945 -0.305054)
			(stroke
				(width 0.1)
				(type default)
			)
			(layer "F.Fab")
		)
		(fp_line
			(start -0.67945 -0.305054)
			(end -0.12065 -0.305054)
			(stroke
				(width 0.1)
				(type default)
			)
			(layer "F.Fab")
		)
		(pad "1" smd circle
			(at -0.40005 0 180)
			(size 0 0)
			(layers "F.Cu" "F.Mask" "F.Paste")
			(net "PWRGD_CHGL_CPU1_R1")
		)
		(pad "2" smd circle
			(at 0.40005 0 180)
			(size 0 0)
			(layers "F.Cu" "F.Mask" "F.Paste")
			(net "PWRGD_CHGL_CPU1_R2")
		)
	)
)
